# T6G (Grand Teton) — schematic netlist excerpt (pin names and nets, part order shuffled) for the footprints in the layout excerpt that follows; sources: Cadence DE-HDL packaged netlist, KiCad conversion of 04192023_DAF0TMB3IC0_F0TG_MB_C_brd_V02_OCP.brd

R3229  Q_RES  200 1% CHIP  pkg 0402LF  page 137 : A = SMB_OCP_V3_2_3V3AUX_BUF_R_SDA ; B = SMB_OCP_V3_2_3V3AUX_BUF_SDA

(kicad_pcb
	(version 20260206)
	(generator "pcbnew")
	(generator_version "10.0")
	(general
		(thickness 1.6)
		(legacy_teardrops no)
	)
	(paper "A4")
	(title_block
		(title "04192023_DAF0TMB3IC0_F0TG_MB_C_brd_V02_OCP.brd")
		(comment 1 "Grand Teton / footprints 446-446 of 8354")
	)
	(layers
		(0 "F.Cu" signal "TOP")
		(4 "In1.Cu" signal "GND")
		(6 "In2.Cu" signal "IN1")
		(8 "In3.Cu" signal "GND1")
		(10 "In4.Cu" signal "IN2")
		(12 "In5.Cu" signal "GND2")
		(14 "In6.Cu" signal "IN3")
		(16 "In7.Cu" signal "GND3")
		(18 "In8.Cu" signal "VCC")
		(20 "In9.Cu" signal "VCC1")
		(22 "In10.Cu" signal "GND4")
		(24 "In11.Cu" signal "IN4")
		(26 "In12.Cu" signal "GND5")
		(28 "In13.Cu" signal "IN5")
		(30 "In14.Cu" signal "GND6")
		(32 "In15.Cu" signal "IN6")
		(34 "In16.Cu" signal "GND7")
		(2 "B.Cu" signal "BOTTOM")
		(9 "F.Adhes" user "F.Adhesive")
		(11 "B.Adhes" user "B.Adhesive")
		(13 "F.Paste" user "Package Geometry/Pastemask Top")
		(15 "B.Paste" user "Package Geometry/Pastemask Bottom")
		(5 "F.SilkS" user "Ref Des/Silkscreen Top")
		(7 "B.SilkS" user "Ref Des/Silkscreen Bottom")
		(1 "F.Mask" user "Board Geometry/Soldermask Top")
		(3 "B.Mask" user "Board Geometry/Soldermask Bottom")
		(17 "Dwgs.User" user "User.Drawings")
		(19 "Cmts.User" user "User.Comments")
		(21 "Eco1.User" user "User.Eco1")
		(23 "Eco2.User" user "User.Eco2")
		(25 "Edge.Cuts" user "Board Geometry/Outline")
		(27 "Margin" user)
		(31 "F.CrtYd" user "Package Geometry/Place Bound Top")
		(29 "B.CrtYd" user "Package Geometry/Place Bound Bottom")
		(35 "F.Fab" user "Ref Des/Assembly Top")
		(33 "B.Fab" user "Ref Des/Assembly Bottom")
	)
	(footprint ""
		(layer "F.Cu")
		(at 152.849326 -36.99256 180)
		(property "Reference" "R3229"
			(at 0 0 180)
			(layer "F.SilkS")
			(hide yes)
			(effects
				(font
					(size 1.27 1.27)
				)
			)
		)
		(property "Value" ""
			(at 0 0 180)
			(layer "F.Fab")
			(effects
				(font
					(size 1.27 1.27)
				)
			)
		)
		(duplicate_pad_numbers_are_jumpers no)
		(fp_line
			(start 0.7874 0.4064)
			(end -0.7874 0.4064)
			(stroke
				(width 0.1524)
				(type default)
			)
			(layer "F.SilkS")
		)
		(fp_line
			(start 0.7874 -0.4064)
			(end 0.7874 0.4064)
			(stroke
				(width 0.1524)
				(type default)
			)
			(layer "F.SilkS")
		)
		(fp_line
			(start -0.7874 0.4064)
			(end -0.7874 -0.4064)
			(stroke
				(width 0.1524)
				(type default)
			)
			(layer "F.SilkS")
		)
		(fp_line
			(start -0.7874 -0.4064)
			(end 0.7874 -0.4064)
			(stroke
				(width 0.1524)
				(type default)
			)
			(layer "F.SilkS")
		)
		(fp_line
			(start 0.67945 0.3048)
			(end 0.120396 0.3048)
			(stroke
				(width 0.1)
				(type default)
			)
			(layer "F.Fab")
		)
		(fp_line
			(start 0.67945 -0.3048)
			(end 0.67945 0.3048)
			(stroke
				(width 0.1)
				(type default)
			)
			(layer "F.Fab")
		)
		(fp_line
			(start 0.12065 -0.2794)
			(end 0.12065 -0.3048)
			(stroke
				(width 0.1)
				(type default)
			)
			(layer "F.Fab")
		)
		(fp_line
			(start 0.12065 -0.3048)
			(end 0.67945 -0.3048)
			(stroke
				(width 0.1)
				(type default)
			)
			(layer "F.Fab")
		)
		(fp_line
			(start 0.120396 0.3048)
			(end 0.120396 0.2794)
			(stroke
				(width 0.1)
				(type default)
			)
			(layer "F.Fab")
		)
		(fp_line
			(start 0.120396 0.2794)
			(end -0.12065 0.2794)
			(stroke
				(width 0.1)
				(type default)
			)
			(layer "F.Fab")
		)
		(fp_line
			(start -0.12065 0.3048)
			(end -0.67945 0.3048)
			(stroke
				(width 0.1)
				(type default)
			)
			(layer "F.Fab")
		)
		(fp_line
			(start -0.12065 0.2794)
			(end -0.12065 0.3048)
			(stroke
				(width 0.1)
				(type default)
			)
			(layer "F.Fab")
		)
		(fp_line
			(start -0.12065 -0.2794)
			(end 0.12065 -0.2794)
			(stroke
				(width 0.1)
				(type default)
			)
			(layer "F.Fab")
		)
		(fp_line
			(start -0.12065 -0.305054)
			(end -0.12065 -0.2794)
			(stroke
				(width 0.1)
				(type default)
			)
			(layer "F.Fab")
		)
		(fp_line
			(start -0.67945 0.3048)
			(end -0.67945 -0.305054)
			(stroke
				(width 0.1)
				(type default)
			)
			(layer "F.Fab")
		)
		(fp_line
			(start -0.67945 -0.305054)
			(end -0.12065 -0.305054)
			(stroke
				(width 0.1)
				(type default)
			)
			(layer "F.Fab")
		)
		(pad "1" smd circle
			(at -0.40005 0 180)
			(size 0 0)
			(layers "F.Cu" "F.Mask" "F.Paste")
			(net "SMB_OCP_V3_2_3V3AUX_BUF_R_SDA")
		)
		(pad "2" smd circle
			(at 0.40005 0 180)
			(size 0 0)
			(layers "F.Cu" "F.Mask" "F.Paste")
			(net "SMB_OCP_V3_2_3V3AUX_BUF_SDA")
		)
	)
)
